# BASEBOARD_FAB2 (Tioga Pass) — schematic netlist excerpt (pin names and nets, part order shuffled) for the footprints in the layout excerpt that follows; sources: Cadence DE-HDL packaged netlist, KiCad conversion of Wiwynn_Tioga_Pass_MB.brd

R8D41  RES  10.0K 1% CHIP  pkg 0402  page 196 : A = P3V3_STBY ; B = PWRGD_P12V_MAIN_R
C9L1  CAP_A  0.01UF 25V 10% X7R  pkg 0402V  page 88 : A = M_M_VREF ; B = GND
R3R10  RES  4.75K 1% CHIP  pkg 0402  page 94 : A = P3V3 ; B = H_CPU1_MEMGHJ_MEMHOT

(kicad_pcb
	(version 20260206)
	(generator "pcbnew")
	(generator_version "10.0")
	(general
		(thickness 1.6)
		(legacy_teardrops no)
	)
	(paper "A4")
	(title_block
		(title "Wiwynn_Tioga_Pass_MB.brd")
		(comment 1 "Tioga Pass / footprints 3408-3410 of 4770")
	)
	(layers
		(0 "F.Cu" signal "TOP")
		(4 "In1.Cu" signal "L2GND")
		(6 "In2.Cu" signal "L3")
		(8 "In3.Cu" signal "L4GND")
		(10 "In4.Cu" signal "L5")
		(12 "In5.Cu" signal "L6GND")
		(14 "In6.Cu" signal "L7VCC")
		(16 "In7.Cu" signal "L8VCC")
		(18 "In8.Cu" signal "L9GND")
		(20 "In9.Cu" signal "L10")
		(22 "In10.Cu" signal "L11GND")
		(24 "In11.Cu" signal "L12")
		(26 "In12.Cu" signal "L13GND")
		(2 "B.Cu" signal "BOTTOM")
		(9 "F.Adhes" user "F.Adhesive")
		(11 "B.Adhes" user "B.Adhesive")
		(13 "F.Paste" user "Package Geometry/Pastemask Top")
		(15 "B.Paste" user "Package Geometry/Pastemask Bottom")
		(5 "F.SilkS" user "Ref Des/Silkscreen Top")
		(7 "B.SilkS" user "Ref Des/Silkscreen Bottom")
		(1 "F.Mask" user "Board Geometry/Soldermask Top")
		(3 "B.Mask" user "Board Geometry/Soldermask Bottom")
		(17 "Dwgs.User" user "User.Drawings")
		(19 "Cmts.User" user "User.Comments")
		(21 "Eco1.User" user "User.Eco1")
		(23 "Eco2.User" user "User.Eco2")
		(25 "Edge.Cuts" user "Board Geometry/Outline")
		(27 "Margin" user)
		(31 "F.CrtYd" user "Package Geometry/Place Bound Top")
		(29 "B.CrtYd" user "Package Geometry/Place Bound Bottom")
		(35 "F.Fab" user "Ref Des/Assembly Top")
		(33 "B.Fab" user "Ref Des/Assembly Bottom")
	)
	(footprint ""
		(layer "B.Cu")
		(at 411.861 -7.4295 180)
		(property "Reference" "R8D41"
			(at 0 0 0)
			(layer "B.SilkS")
			(hide yes)
			(effects
				(font
					(size 1.27 1.27)
				)
				(justify mirror)
			)
		)
		(property "Value" ""
			(at 0 0 0)
			(layer "B.Fab")
			(effects
				(font
					(size 1.27 1.27)
				)
				(justify mirror)
			)
		)
		(duplicate_pad_numbers_are_jumpers no)
		(fp_poly
			(pts
				(xy 0.2794 -0.1016) (xy -0.2794 -0.1016) (xy -0.2794 0.9906) (xy 0.2794 0.9906)
			)
			(stroke
				(width 0)
				(type default)
			)
			(fill no)
			(layer "B.CrtYd")
		)
		(fp_line
			(start 0.2794 0.9906)
			(end -0.2794 0.9906)
			(stroke
				(width 0.1)
				(type default)
			)
			(layer "B.Fab")
		)
		(fp_line
			(start 0.2794 -0.1016)
			(end 0.2794 0.9906)
			(stroke
				(width 0.1)
				(type default)
			)
			(layer "B.Fab")
		)
		(fp_line
			(start -0.2794 0.9906)
			(end -0.2794 -0.1016)
			(stroke
				(width 0.1)
				(type default)
			)
			(layer "B.Fab")
		)
		(fp_line
			(start -0.2794 -0.1016)
			(end 0.2794 -0.1016)
			(stroke
				(width 0.1)
				(type default)
			)
			(layer "B.Fab")
		)
		(pad "1" smd rect
			(at 0 0)
			(size 0.508 0.508)
			(layers "B.Cu" "B.Mask" "B.Paste")
			(net "P3V3_STBY")
		)
		(pad "2" smd rect
			(at 0 0.889)
			(size 0.508 0.508)
			(layers "B.Cu" "B.Mask" "B.Paste")
			(net "PWRGD_P12V_MAIN_R")
		)
		(zone
			(layer "B.Cu")
			(hatch none 0.5)
			(connect_pads
				(clearance 0)
			)
			(min_thickness 0.25)
			(keepout
				(tracks not_allowed)
				(vias allowed)
				(pads allowed)
				(copperpour not_allowed)
				(footprints allowed)
			)
			(placement
				(enabled no)
				(sheetname "")
			)
			(fill
				(thermal_gap 0.5)
				(thermal_bridge_width 0.5)
				(island_removal_mode 0)
			)
			(polygon
				(pts
					(xy 411.607 -8.0645) (xy 412.115 -8.0645) (xy 412.115 -7.6835) (xy 411.607 -7.6835)
				)
			)
		)
		(zone
			(layer "B.Cu")
			(hatch none 0.5)
			(connect_pads
				(clearance 0)
			)
			(min_thickness 0.25)
			(keepout
				(tracks allowed)
				(vias not_allowed)
				(pads allowed)
				(copperpour not_allowed)
				(footprints allowed)
			)
			(placement
				(enabled no)
				(sheetname "")
			)
			(fill
				(thermal_gap 0.5)
				(thermal_bridge_width 0.5)
				(island_removal_mode 0)
			)
			(polygon
				(pts
					(xy 411.607 -7.6835) (xy 412.115 -7.6835) (xy 412.115 -8.0645) (xy 411.607 -8.0645)
				)
			)
		)
	)
	(footprint ""
		(layer "B.Cu")
		(at 413.9438 -89.4207 -90)
		(property "Reference" "R3R10"
			(at 0 0 90)
			(layer "B.SilkS")
			(hide yes)
			(effects
				(font
					(size 1.27 1.27)
				)
				(justify mirror)
			)
		)
		(property "Value" ""
			(at 0 0 90)
			(layer "B.Fab")
			(effects
				(font
					(size 1.27 1.27)
				)
				(justify mirror)
			)
		)
		(duplicate_pad_numbers_are_jumpers no)
		(fp_poly
			(pts
				(xy 0.2794 -0.1016) (xy -0.2794 -0.1016) (xy -0.2794 0.9906) (xy 0.2794 0.9906)
			)
			(stroke
				(width 0)
				(type default)
			)
			(fill no)
			(layer "B.CrtYd")
		)
		(fp_line
			(start -0.2794 0.9906)
			(end -0.2794 -0.1016)
			(stroke
				(width 0.1)
				(type default)
			)
			(layer "B.Fab")
		)
		(fp_line
			(start 0.2794 0.9906)
			(end -0.2794 0.9906)
			(stroke
				(width 0.1)
				(type default)
			)
			(layer "B.Fab")
		)
		(fp_line
			(start -0.2794 -0.1016)
			(end 0.2794 -0.1016)
			(stroke
				(width 0.1)
				(type default)
			)
			(layer "B.Fab")
		)
		(fp_line
			(start 0.2794 -0.1016)
			(end 0.2794 0.9906)
			(stroke
				(width 0.1)
				(type default)
			)
			(layer "B.Fab")
		)
		(pad "1" smd rect
			(at 0 0 90)
			(size 0.508 0.508)
			(layers "B.Cu" "B.Mask" "B.Paste")
			(net "P3V3")
		)
		(pad "2" smd rect
			(at 0 0.889 90)
			(size 0.508 0.508)
			(layers "B.Cu" "B.Mask" "B.Paste")
			(net "H_CPU1_MEMGHJ_MEMHOT")
		)
		(zone
			(layer "B.Cu")
			(hatch none 0.5)
			(connect_pads
				(clearance 0)
			)
			(min_thickness 0.25)
			(keepout
				(tracks not_allowed)
				(vias allowed)
				(pads allowed)
				(copperpour not_allowed)
				(footprints allowed)
			)
			(placement
				(enabled no)
				(sheetname "")
			)
			(fill
				(thermal_gap 0.5)
				(thermal_bridge_width 0.5)
				(island_removal_mode 0)
			)
			(polygon
				(pts
					(xy 413.3088 -89.1667) (xy 413.3088 -89.6747) (xy 413.6898 -89.6747) (xy 413.6898 -89.1667)
				)
			)
		)
		(zone
			(layer "B.Cu")
			(hatch none 0.5)
			(connect_pads
				(clearance 0)
			)
			(min_thickness 0.25)
			(keepout
				(tracks allowed)
				(vias not_allowed)
				(pads allowed)
				(copperpour not_allowed)
				(footprints allowed)
			)
			(placement
				(enabled no)
				(sheetname "")
			)
			(fill
				(thermal_gap 0.5)
				(thermal_bridge_width 0.5)
				(island_removal_mode 0)
			)
			(polygon
				(pts
					(xy 413.6898 -89.1667) (xy 413.6898 -89.6747) (xy 413.3088 -89.6747) (xy 413.3088 -89.1667)
				)
			)
		)
	)
	(footprint ""
		(layer "B.Cu")
		(at 30.452568 -154.6352 90)
		(property "Reference" "C9L1"
			(at 0 0 90)
			(layer "B.SilkS")
			(hide yes)
			(effects
				(font
					(size 1.27 1.27)
				)
				(justify mirror)
			)
		)
		(property "Value" ""
			(at 0 0 90)
			(layer "B.Fab")
			(effects
				(font
					(size 1.27 1.27)
				)
				(justify mirror)
			)
		)
		(duplicate_pad_numbers_are_jumpers no)
		(fp_poly
			(pts
				(xy -0.3048 -0.1016) (xy -0.3048 0.9906) (xy 0.3048 0.9906) (xy 0.3048 -0.1016)
			)
			(stroke
				(width 0)
				(type default)
			)
			(fill no)
			(layer "B.CrtYd")
		)
		(fp_line
			(start 0.3048 -0.1016)
			(end 0.3048 0.9906)
			(stroke
				(width 0.1)
				(type default)
			)
			(layer "B.Fab")
		)
		(fp_line
			(start -0.3048 -0.1016)
			(end 0.3048 -0.1016)
			(stroke
				(width 0.1)
				(type default)
			)
			(layer "B.Fab")
		)
		(fp_line
			(start 0.3048 0.9906)
			(end -0.3048 0.9906)
			(stroke
				(width 0.1)
				(type default)
			)
			(layer "B.Fab")
		)
		(fp_line
			(start -0.3048 0.9906)
			(end -0.3048 -0.1016)
			(stroke
				(width 0.1)
				(type default)
			)
			(layer "B.Fab")
		)
		(pad "1" smd rect
			(at 0 0 270)
			(size 0.508 0.508)
			(layers "B.Cu" "B.Mask" "B.Paste")
			(net "M_M_VREF")
		)
		(pad "2" smd rect
			(at 0 0.889 270)
			(size 0.508 0.508)
			(layers "B.Cu" "B.Mask" "B.Paste")
			(net "GND")
		)
		(zone
			(layer "B.Cu")
			(hatch none 0.5)
			(connect_pads
				(clearance 0)
			)
			(min_thickness 0.25)
			(keepout
				(tracks allowed)
				(vias not_allowed)
				(pads allowed)
				(copperpour not_allowed)
				(footprints allowed)
			)
			(placement
				(enabled no)
				(sheetname "")
			)
			(fill
				(thermal_gap 0.5)
				(thermal_bridge_width 0.5)
				(island_removal_mode 0)
			)
			(polygon
				(pts
					(xy 30.706568 -154.8892) (xy 30.706568 -154.3812) (xy 31.087568 -154.3812) (xy 31.087568 -154.8892)
				)
			)
		)
		(zone
			(layer "B.Cu")
			(hatch none 0.5)
			(connect_pads
				(clearance 0)
			)
			(min_thickness 0.25)
			(keepout
				(tracks not_allowed)
				(vias allowed)
				(pads allowed)
				(copperpour not_allowed)
				(footprints allowed)
			)
			(placement
				(enabled no)
				(sheetname "")
			)
			(fill
				(thermal_gap 0.5)
				(thermal_bridge_width 0.5)
				(island_removal_mode 0)
			)
			(polygon
				(pts
					(xy 31.087568 -154.8892) (xy 31.087568 -154.3812) (xy 30.706568 -154.3812) (xy 30.706568 -154.8892)
				)
			)
		)
	)
)
